# T6G (Grand Teton) — schematic netlist excerpt (pin names and nets, part order shuffled) for the footprints in the layout excerpt that follows; sources: Cadence DE-HDL packaged netlist, KiCad conversion of 04192023_DAF0TMB3IC0_F0TG_MB_C_brd_V02_OCP.brd

R37  Q_RES  10K 1% CHIP  pkg 0402LF  page 104 : A = PD_CHG_CPU1_DIMM0_SAA ; B = GND
R580  Q_RES  10K 1% CHIP  pkg 0402LF  page 183 : A = P3V3_AUX ; B = CLK_9ZXL045_P1_HIBW

(kicad_pcb
	(version 20260206)
	(generator "pcbnew")
	(generator_version "10.0")
	(general
		(thickness 1.6)
		(legacy_teardrops no)
	)
	(paper "A4")
	(title_block
		(title "04192023_DAF0TMB3IC0_F0TG_MB_C_brd_V02_OCP.brd")
		(comment 1 "Grand Teton / footprints 7031-7032 of 8354")
	)
	(layers
		(0 "F.Cu" signal "TOP")
		(4 "In1.Cu" signal "GND")
		(6 "In2.Cu" signal "IN1")
		(8 "In3.Cu" signal "GND1")
		(10 "In4.Cu" signal "IN2")
		(12 "In5.Cu" signal "GND2")
		(14 "In6.Cu" signal "IN3")
		(16 "In7.Cu" signal "GND3")
		(18 "In8.Cu" signal "VCC")
		(20 "In9.Cu" signal "VCC1")
		(22 "In10.Cu" signal "GND4")
		(24 "In11.Cu" signal "IN4")
		(26 "In12.Cu" signal "GND5")
		(28 "In13.Cu" signal "IN5")
		(30 "In14.Cu" signal "GND6")
		(32 "In15.Cu" signal "IN6")
		(34 "In16.Cu" signal "GND7")
		(2 "B.Cu" signal "BOTTOM")
		(9 "F.Adhes" user "F.Adhesive")
		(11 "B.Adhes" user "B.Adhesive")
		(13 "F.Paste" user "Package Geometry/Pastemask Top")
		(15 "B.Paste" user "Package Geometry/Pastemask Bottom")
		(5 "F.SilkS" user "Ref Des/Silkscreen Top")
		(7 "B.SilkS" user "Ref Des/Silkscreen Bottom")
		(1 "F.Mask" user "Board Geometry/Soldermask Top")
		(3 "B.Mask" user "Board Geometry/Soldermask Bottom")
		(17 "Dwgs.User" user "User.Drawings")
		(19 "Cmts.User" user "User.Comments")
		(21 "Eco1.User" user "User.Eco1")
		(23 "Eco2.User" user "User.Eco2")
		(25 "Edge.Cuts" user "Board Geometry/Outline")
		(27 "Margin" user)
		(31 "F.CrtYd" user "Package Geometry/Place Bound Top")
		(29 "B.CrtYd" user "Package Geometry/Place Bound Bottom")
		(35 "F.Fab" user "Ref Des/Assembly Top")
		(33 "B.Fab" user "Ref Des/Assembly Bottom")
	)
	(footprint ""
		(layer "B.Cu")
		(at 111.887 -414.02)
		(property "Reference" "R580"
			(at 0 0 0)
			(layer "B.SilkS")
			(hide yes)
			(effects
				(font
					(size 1.27 1.27)
				)
				(justify mirror)
			)
		)
		(property "Value" ""
			(at 0 0 0)
			(layer "B.Fab")
			(effects
				(font
					(size 1.27 1.27)
				)
				(justify mirror)
			)
		)
		(duplicate_pad_numbers_are_jumpers no)
		(fp_line
			(start -0.7874 -0.4064)
			(end -0.7874 0.4064)
			(stroke
				(width 0.1524)
				(type default)
			)
			(layer "B.SilkS")
		)
		(fp_line
			(start -0.7874 0.4064)
			(end 0.7874 0.4064)
			(stroke
				(width 0.1524)
				(type default)
			)
			(layer "B.SilkS")
		)
		(fp_line
			(start 0.7874 -0.4064)
			(end -0.7874 -0.4064)
			(stroke
				(width 0.1524)
				(type default)
			)
			(layer "B.SilkS")
		)
		(fp_line
			(start 0.7874 0.4064)
			(end 0.7874 -0.4064)
			(stroke
				(width 0.1524)
				(type default)
			)
			(layer "B.SilkS")
		)
		(fp_line
			(start -0.67945 -0.3048)
			(end -0.67945 0.3048)
			(stroke
				(width 0.1)
				(type default)
			)
			(layer "B.Fab")
		)
		(fp_line
			(start -0.67945 0.3048)
			(end -0.120396 0.3048)
			(stroke
				(width 0.1)
				(type default)
			)
			(layer "B.Fab")
		)
		(fp_line
			(start -0.12065 -0.3048)
			(end -0.67945 -0.3048)
			(stroke
				(width 0.1)
				(type default)
			)
			(layer "B.Fab")
		)
		(fp_line
			(start -0.12065 -0.2794)
			(end -0.12065 -0.3048)
			(stroke
				(width 0.1)
				(type default)
			)
			(layer "B.Fab")
		)
		(fp_line
			(start -0.120396 0.2794)
			(end 0.12065 0.2794)
			(stroke
				(width 0.1)
				(type default)
			)
			(layer "B.Fab")
		)
		(fp_line
			(start -0.120396 0.3048)
			(end -0.120396 0.2794)
			(stroke
				(width 0.1)
				(type default)
			)
			(layer "B.Fab")
		)
		(fp_line
			(start 0.12065 -0.305054)
			(end 0.12065 -0.2794)
			(stroke
				(width 0.1)
				(type default)
			)
			(layer "B.Fab")
		)
		(fp_line
			(start 0.12065 -0.2794)
			(end -0.12065 -0.2794)
			(stroke
				(width 0.1)
				(type default)
			)
			(layer "B.Fab")
		)
		(fp_line
			(start 0.12065 0.2794)
			(end 0.12065 0.3048)
			(stroke
				(width 0.1)
				(type default)
			)
			(layer "B.Fab")
		)
		(fp_line
			(start 0.12065 0.3048)
			(end 0.67945 0.3048)
			(stroke
				(width 0.1)
				(type default)
			)
			(layer "B.Fab")
		)
		(fp_line
			(start 0.67945 -0.305054)
			(end 0.12065 -0.305054)
			(stroke
				(width 0.1)
				(type default)
			)
			(layer "B.Fab")
		)
		(fp_line
			(start 0.67945 0.3048)
			(end 0.67945 -0.305054)
			(stroke
				(width 0.1)
				(type default)
			)
			(layer "B.Fab")
		)
		(pad "1" smd circle
			(at 0.40005 0 180)
			(size 0 0)
			(layers "B.Cu" "B.Mask" "B.Paste")
			(net "P3V3_AUX")
		)
		(pad "2" smd circle
			(at -0.40005 0 180)
			(size 0 0)
			(layers "B.Cu" "B.Mask" "B.Paste")
			(net "CLK_9ZXL045_P1_HIBW")
		)
	)
	(footprint ""
		(layer "B.Cu")
		(at 165.183566 -194.885564 180)
		(property "Reference" "R37"
			(at 0 0 0)
			(layer "B.SilkS")
			(hide yes)
			(effects
				(font
					(size 1.27 1.27)
				)
				(justify mirror)
			)
		)
		(property "Value" ""
			(at 0 0 0)
			(layer "B.Fab")
			(effects
				(font
					(size 1.27 1.27)
				)
				(justify mirror)
			)
		)
		(duplicate_pad_numbers_are_jumpers no)
		(fp_line
			(start 0.7874 0.4064)
			(end 0.7874 -0.4064)
			(stroke
				(width 0.1524)
				(type default)
			)
			(layer "B.SilkS")
		)
		(fp_line
			(start 0.7874 -0.4064)
			(end -0.7874 -0.4064)
			(stroke
				(width 0.1524)
				(type default)
			)
			(layer "B.SilkS")
		)
		(fp_line
			(start -0.7874 0.4064)
			(end 0.7874 0.4064)
			(stroke
				(width 0.1524)
				(type default)
			)
			(layer "B.SilkS")
		)
		(fp_line
			(start -0.7874 -0.4064)
			(end -0.7874 0.4064)
			(stroke
				(width 0.1524)
				(type default)
			)
			(layer "B.SilkS")
		)
		(fp_line
			(start 0.67945 0.3048)
			(end 0.67945 -0.305054)
			(stroke
				(width 0.1)
				(type default)
			)
			(layer "B.Fab")
		)
		(fp_line
			(start 0.67945 -0.305054)
			(end 0.12065 -0.305054)
			(stroke
				(width 0.1)
				(type default)
			)
			(layer "B.Fab")
		)
		(fp_line
			(start 0.12065 0.3048)
			(end 0.67945 0.3048)
			(stroke
				(width 0.1)
				(type default)
			)
			(layer "B.Fab")
		)
		(fp_line
			(start 0.12065 0.2794)
			(end 0.12065 0.3048)
			(stroke
				(width 0.1)
				(type default)
			)
			(layer "B.Fab")
		)
		(fp_line
			(start 0.12065 -0.2794)
			(end -0.12065 -0.2794)
			(stroke
				(width 0.1)
				(type default)
			)
			(layer "B.Fab")
		)
		(fp_line
			(start 0.12065 -0.305054)
			(end 0.12065 -0.2794)
			(stroke
				(width 0.1)
				(type default)
			)
			(layer "B.Fab")
		)
		(fp_line
			(start -0.120396 0.3048)
			(end -0.120396 0.2794)
			(stroke
				(width 0.1)
				(type default)
			)
			(layer "B.Fab")
		)
		(fp_line
			(start -0.120396 0.2794)
			(end 0.12065 0.2794)
			(stroke
				(width 0.1)
				(type default)
			)
			(layer "B.Fab")
		)
		(fp_line
			(start -0.12065 -0.2794)
			(end -0.12065 -0.3048)
			(stroke
				(width 0.1)
				(type default)
			)
			(layer "B.Fab")
		)
		(fp_line
			(start -0.12065 -0.3048)
			(end -0.67945 -0.3048)
			(stroke
				(width 0.1)
				(type default)
			)
			(layer "B.Fab")
		)
		(fp_line
			(start -0.67945 0.3048)
			(end -0.120396 0.3048)
			(stroke
				(width 0.1)
				(type default)
			)
			(layer "B.Fab")
		)
		(fp_line
			(start -0.67945 -0.3048)
			(end -0.67945 0.3048)
			(stroke
				(width 0.1)
				(type default)
			)
			(layer "B.Fab")
		)
		(pad "1" smd circle
			(at 0.40005 0)
			(size 0 0)
			(layers "B.Cu" "B.Mask" "B.Paste")
			(net "PD_CHG_CPU1_DIMM0_SAA")
		)
		(pad "2" smd circle
			(at -0.40005 0)
			(size 0 0)
			(layers "B.Cu" "B.Mask" "B.Paste")
			(net "GND")
		)
	)
)
